(kicad_pcb
	(version 20260206)
	(generator "pcbnew")
	(generator_version "10.0")
	(general
		(thickness 1.6)
		(legacy_teardrops no)
	)
	(paper "A4")
	(title_block
		(title "fcb — 12433-1M.1206WZS1330.brd")
		(comment 1 "Open Vault / Knox (Wiwynn) / footprints 295-301 of 495")
	)
	(layers
		(0 "F.Cu" signal "TOP")
		(4 "In1.Cu" signal "L2GND")
		(6 "In2.Cu" signal "L3VCC")
		(2 "B.Cu" signal "BOTTOM")
		(9 "F.Adhes" user "F.Adhesive")
		(11 "B.Adhes" user "B.Adhesive")
		(13 "F.Paste" user "Package Geometry/Pastemask Top")
		(15 "B.Paste" user "Package Geometry/Pastemask Bottom")
		(5 "F.SilkS" user "Ref Des/Silkscreen Top")
		(7 "B.SilkS" user "Ref Des/Silkscreen Bottom")
		(1 "F.Mask" user "Board Geometry/Soldermask Top")
		(3 "B.Mask" user "Board Geometry/Soldermask Bottom")
		(17 "Dwgs.User" user "User.Drawings")
		(19 "Cmts.User" user "User.Comments")
		(21 "Eco1.User" user "User.Eco1")
		(23 "Eco2.User" user "User.Eco2")
		(25 "Edge.Cuts" user "Board Geometry/Outline")
		(27 "Margin" user)
		(31 "F.CrtYd" user "Package Geometry/Place Bound Top")
		(29 "B.CrtYd" user "Package Geometry/Place Bound Bottom")
		(35 "F.Fab" user "Ref Des/Assembly Top")
		(33 "B.Fab" user "Ref Des/Assembly Bottom")
	)
	(footprint ""
		(layer "F.Cu")
		(at 38.227 -178.054 180)
		(property "Reference" "C254"
			(at 0 0 180)
			(layer "F.SilkS")
			(hide yes)
			(effects
				(font
					(size 1.27 1.27)
				)
			)
		)
		(property "Value" "SCD1U16V2KX-3GP"
			(at 1.1811 -2.7051 180)
			(unlocked yes)
			(layer "F.Fab")
			(hide yes)
			(effects
				(font
					(size 1.016 1.016)
					(thickness 0.1524)
				)
			)
		)
		(property "Device Type" "C402H22"
			(at 1.1811 -4.2291 180)
			(unlocked yes)
			(layer "F.Fab")
			(hide yes)
			(effects
				(font
					(size 1.016 1.016)
					(thickness 0.1524)
				)
			)
		)
		(duplicate_pad_numbers_are_jumpers no)
		(fp_rect
			(start -0.4318 0.9525)
			(end 0.4318 -0.9525)
			(stroke
				(width 0)
				(type default)
			)
			(fill no)
			(layer "F.CrtYd")
		)
		(fp_rect
			(start -0.4318 0.9525)
			(end 0.4318 -0.9525)
			(stroke
				(width 0)
				(type default)
			)
			(fill no)
			(layer "F.Fab")
		)
		(pad "1" smd custom
			(at 0 -0.4445 180)
			(size 0.1524 0.1524)
			(layers "F.Cu" "F.Mask" "F.Paste")
			(net "P3V3_AUX")
			(options
				(clearance outline)
				(anchor circle)
			)
			(primitives
				(gr_poly
					(pts
						(arc
							(start 0.3048 -0.2032)
							(mid 0.275042 -0.275042)
							(end 0.2032 -0.3048)
						)
						(arc
							(start -0.2032 -0.3048)
							(mid -0.275042 -0.275042)
							(end -0.3048 -0.2032)
						)
						(arc
							(start -0.3048 0.2032)
							(mid -0.275042 0.275042)
							(end -0.2032 0.3048)
						)
						(arc
							(start 0.2032 0.3048)
							(mid 0.275042 0.275042)
							(end 0.3048 0.2032)
						)
					)
					(width 0)
					(fill yes)
				)
			)
		)
		(pad "2" smd custom
			(at 0 0.4445 180)
			(size 0.1524 0.1524)
			(layers "F.Cu" "F.Mask" "F.Paste")
			(net "GND")
			(options
				(clearance outline)
				(anchor circle)
			)
			(primitives
				(gr_poly
					(pts
						(arc
							(start 0.3048 -0.2032)
							(mid 0.275042 -0.275042)
							(end 0.2032 -0.3048)
						)
						(arc
							(start -0.2032 -0.3048)
							(mid -0.275042 -0.275042)
							(end -0.3048 -0.2032)
						)
						(arc
							(start -0.3048 0.2032)
							(mid -0.275042 0.275042)
							(end -0.2032 0.3048)
						)
						(arc
							(start 0.2032 0.3048)
							(mid 0.275042 0.275042)
							(end 0.3048 0.2032)
						)
					)
					(width 0)
					(fill yes)
				)
			)
		)
	)
	(footprint ""
		(layer "F.Cu")
		(at 24.1808 -168.656)
		(property "Reference" "R20"
			(at 0 0 0)
			(layer "F.SilkS")
			(hide yes)
			(effects
				(font
					(size 1.27 1.27)
				)
			)
		)
		(property "Value" "4K7R2F-GP"
			(at 0.064008 -3.993896 0)
			(unlocked yes)
			(layer "F.Fab")
			(hide yes)
			(effects
				(font
					(size 1.016 1.016)
					(thickness 0.1524)
				)
			)
		)
		(property "Device Type" "R402H16"
			(at 0.064008 -5.517896 0)
			(unlocked yes)
			(layer "F.Fab")
			(hide yes)
			(effects
				(font
					(size 1.016 1.016)
					(thickness 0.1524)
				)
			)
		)
		(duplicate_pad_numbers_are_jumpers no)
		(fp_line
			(start -0.508 -0.9398)
			(end -0.508 0.9398)
			(stroke
				(width 0.1524)
				(type default)
			)
			(layer "F.SilkS")
		)
		(fp_line
			(start 0.508 -0.9398)
			(end -0.508 -0.9398)
			(stroke
				(width 0.1524)
				(type default)
			)
			(layer "F.SilkS")
		)
		(fp_rect
			(start -0.508 0.9398)
			(end 0.508 -0.9398)
			(stroke
				(width 0)
				(type default)
			)
			(fill no)
			(layer "F.CrtYd")
		)
		(fp_rect
			(start -0.508 0.9398)
			(end 0.508 -0.9398)
			(stroke
				(width 0)
				(type default)
			)
			(fill no)
			(layer "F.Fab")
		)
		(pad "1" smd custom
			(at 0 -0.4445)
			(size 0.1397 0.1397)
			(layers "F.Cu" "F.Mask" "F.Paste")
			(net "P3V3")
			(options
				(clearance outline)
				(anchor circle)
			)
			(primitives
				(gr_poly
					(pts
						(arc
							(start -0.1778 -0.2794)
							(mid -0.249642 -0.249642)
							(end -0.2794 -0.1778)
						)
						(arc
							(start -0.2794 0.1778)
							(mid -0.249642 0.249642)
							(end -0.1778 0.2794)
						)
						(arc
							(start 0.1778 0.2794)
							(mid 0.249642 0.249642)
							(end 0.2794 0.1778)
						)
						(arc
							(start 0.2794 -0.1778)
							(mid 0.249642 -0.249642)
							(end 0.1778 -0.2794)
						)
					)
					(width 0)
					(fill yes)
				)
			)
		)
		(pad "2" smd custom
			(at 0 0.4445)
			(size 0.1397 0.1397)
			(layers "F.Cu" "F.Mask" "F.Paste")
			(net "PWM_BUFFER_IN_FAN5_FAN6")
			(options
				(clearance outline)
				(anchor circle)
			)
			(primitives
				(gr_poly
					(pts
						(arc
							(start -0.1778 -0.2794)
							(mid -0.249642 -0.249642)
							(end -0.2794 -0.1778)
						)
						(arc
							(start -0.2794 0.1778)
							(mid -0.249642 0.249642)
							(end -0.1778 0.2794)
						)
						(arc
							(start 0.1778 0.2794)
							(mid 0.249642 0.249642)
							(end 0.2794 0.1778)
						)
						(arc
							(start 0.2794 -0.1778)
							(mid 0.249642 -0.249642)
							(end 0.1778 -0.2794)
						)
					)
					(width 0)
					(fill yes)
				)
			)
		)
	)
	(footprint ""
		(layer "F.Cu")
		(at 16.51 -148.336 -90)
		(property "Reference" "D4"
			(at 0 0 270)
			(layer "F.SilkS")
			(hide yes)
			(effects
				(font
					(size 1.27 1.27)
				)
			)
		)
		(property "Value" "BAS16H-GP"
			(at 0 -5.5372 270)
			(unlocked yes)
			(layer "F.Fab")
			(hide yes)
			(effects
				(font
					(size 1.016 1.016)
					(thickness 0.1524)
				)
			)
		)
		(property "Device Type" "SOD123AKH48"
			(at 0 -7.0612 270)
			(unlocked yes)
			(layer "F.Fab")
			(hide yes)
			(effects
				(font
					(size 1.016 1.016)
					(thickness 0.1524)
				)
			)
		)
		(duplicate_pad_numbers_are_jumpers no)
		(fp_line
			(start 0.889 2.921)
			(end -0.889 2.921)
			(stroke
				(width 0.508)
				(type default)
			)
			(layer "F.SilkS")
		)
		(fp_line
			(start -1.016 2.667)
			(end 1.016 2.667)
			(stroke
				(width 0.1524)
				(type default)
			)
			(layer "F.SilkS")
		)
		(fp_line
			(start 1.016 2.667)
			(end 1.016 -2.667)
			(stroke
				(width 0.1524)
				(type default)
			)
			(layer "F.SilkS")
		)
		(fp_line
			(start -1.016 -2.667)
			(end -1.016 2.667)
			(stroke
				(width 0.1524)
				(type default)
			)
			(layer "F.SilkS")
		)
		(fp_line
			(start 1.016 -2.667)
			(end -1.016 -2.667)
			(stroke
				(width 0.1524)
				(type default)
			)
			(layer "F.SilkS")
		)
		(fp_rect
			(start -1.143 3.175)
			(end 1.143 -2.794)
			(stroke
				(width 0)
				(type default)
			)
			(fill no)
			(layer "F.CrtYd")
		)
		(fp_poly
			(pts
				(xy -1.143 -2.794) (xy 1.143 -2.794) (xy 1.143 3.175) (xy -1.143 3.175)
			)
			(stroke
				(width 0)
				(type default)
			)
			(fill no)
			(layer "F.Fab")
		)
		(pad "A" smd rect
			(at 0 -1.6891 270)
			(size 0.889 1.397)
			(layers "F.Cu" "F.Mask" "F.Paste")
			(net "FAN_TACH9")
		)
		(pad "K" smd rect
			(at 0 1.6891 270)
			(size 0.889 1.397)
			(layers "F.Cu" "F.Mask" "F.Paste")
			(net "P12V")
		)
	)
	(footprint ""
		(layer "F.Cu")
		(at 36.63569 -165.513766 180)
		(property "Reference" "R1"
			(at 0 0 180)
			(layer "F.SilkS")
			(hide yes)
			(effects
				(font
					(size 1.27 1.27)
				)
			)
		)
		(property "Value" "0R2J-2-GP"
			(at 0.064008 -3.993896 180)
			(unlocked yes)
			(layer "F.Fab")
			(hide yes)
			(effects
				(font
					(size 1.016 1.016)
					(thickness 0.1524)
				)
			)
		)
		(property "Device Type" "R402H16"
			(at 0.064008 -5.517896 180)
			(unlocked yes)
			(layer "F.Fab")
			(hide yes)
			(effects
				(font
					(size 1.016 1.016)
					(thickness 0.1524)
				)
			)
		)
		(duplicate_pad_numbers_are_jumpers no)
		(fp_line
			(start 0.508 -0.9398)
			(end -0.508 -0.9398)
			(stroke
				(width 0.1524)
				(type default)
			)
			(layer "F.SilkS")
		)
		(fp_line
			(start -0.508 -0.9398)
			(end -0.508 0.9398)
			(stroke
				(width 0.1524)
				(type default)
			)
			(layer "F.SilkS")
		)
		(fp_rect
			(start -0.508 0.9398)
			(end 0.508 -0.9398)
			(stroke
				(width 0)
				(type default)
			)
			(fill no)
			(layer "F.CrtYd")
		)
		(fp_rect
			(start -0.508 0.9398)
			(end 0.508 -0.9398)
			(stroke
				(width 0)
				(type default)
			)
			(fill no)
			(layer "F.Fab")
		)
		(pad "1" smd custom
			(at 0 -0.4445 180)
			(size 0.1397 0.1397)
			(layers "F.Cu" "F.Mask" "F.Paste")
			(net "I2C_C_SDA_NCT7904")
			(options
				(clearance outline)
				(anchor circle)
			)
			(primitives
				(gr_poly
					(pts
						(arc
							(start -0.1778 -0.2794)
							(mid -0.249642 -0.249642)
							(end -0.2794 -0.1778)
						)
						(arc
							(start -0.2794 0.1778)
							(mid -0.249642 0.249642)
							(end -0.1778 0.2794)
						)
						(arc
							(start 0.1778 0.2794)
							(mid 0.249642 0.249642)
							(end 0.2794 0.1778)
						)
						(arc
							(start 0.2794 -0.1778)
							(mid 0.249642 -0.249642)
							(end 0.1778 -0.2794)
						)
					)
					(width 0)
					(fill yes)
				)
			)
		)
		(pad "2" smd custom
			(at 0 0.4445 180)
			(size 0.1397 0.1397)
			(layers "F.Cu" "F.Mask" "F.Paste")
			(net "I2C_C_SDA")
			(options
				(clearance outline)
				(anchor circle)
			)
			(primitives
				(gr_poly
					(pts
						(arc
							(start -0.1778 -0.2794)
							(mid -0.249642 -0.249642)
							(end -0.2794 -0.1778)
						)
						(arc
							(start -0.2794 0.1778)
							(mid -0.249642 0.249642)
							(end -0.1778 0.2794)
						)
						(arc
							(start 0.1778 0.2794)
							(mid 0.249642 0.249642)
							(end 0.2794 0.1778)
						)
						(arc
							(start 0.2794 -0.1778)
							(mid 0.249642 -0.249642)
							(end 0.1778 -0.2794)
						)
					)
					(width 0)
					(fill yes)
				)
			)
		)
	)
	(footprint ""
		(layer "F.Cu")
		(at 40.132 -146.5326)
		(property "Reference" "PR109"
			(at 0 0 0)
			(layer "F.SilkS")
			(hide yes)
			(effects
				(font
					(size 1.27 1.27)
				)
			)
		)
		(property "Value" "6K81R2F-1-GP"
			(at 0.064008 -3.993896 0)
			(unlocked yes)
			(layer "F.Fab")
			(hide yes)
			(effects
				(font
					(size 1.016 1.016)
					(thickness 0.1524)
				)
			)
		)
		(property "Device Type" "R402H16"
			(at 0.064008 -5.517896 0)
			(unlocked yes)
			(layer "F.Fab")
			(hide yes)
			(effects
				(font
					(size 1.016 1.016)
					(thickness 0.1524)
				)
			)
		)
		(duplicate_pad_numbers_are_jumpers no)
		(fp_line
			(start -0.508 -0.9398)
			(end -0.508 0.9398)
			(stroke
				(width 0.1524)
				(type default)
			)
			(layer "F.SilkS")
		)
		(fp_line
			(start 0.508 -0.9398)
			(end -0.508 -0.9398)
			(stroke
				(width 0.1524)
				(type default)
			)
			(layer "F.SilkS")
		)
		(fp_rect
			(start -0.508 0.9398)
			(end 0.508 -0.9398)
			(stroke
				(width 0)
				(type default)
			)
			(fill no)
			(layer "F.CrtYd")
		)
		(fp_rect
			(start -0.508 0.9398)
			(end 0.508 -0.9398)
			(stroke
				(width 0)
				(type default)
			)
			(fill no)
			(layer "F.Fab")
		)
		(pad "1" smd custom
			(at 0 -0.4445)
			(size 0.1397 0.1397)
			(layers "F.Cu" "F.Mask" "F.Paste")
			(net "P12V")
			(options
				(clearance outline)
				(anchor circle)
			)
			(primitives
				(gr_poly
					(pts
						(arc
							(start -0.1778 -0.2794)
							(mid -0.249642 -0.249642)
							(end -0.2794 -0.1778)
						)
						(arc
							(start -0.2794 0.1778)
							(mid -0.249642 0.249642)
							(end -0.1778 0.2794)
						)
						(arc
							(start 0.1778 0.2794)
							(mid 0.249642 0.249642)
							(end 0.2794 0.1778)
						)
						(arc
							(start 0.2794 -0.1778)
							(mid 0.249642 -0.249642)
							(end 0.1778 -0.2794)
						)
					)
					(width 0)
					(fill yes)
				)
			)
		)
		(pad "2" smd custom
			(at 0 0.4445)
			(size 0.1397 0.1397)
			(layers "F.Cu" "F.Mask" "F.Paste")
			(net "P12VL_2490_EN_1")
			(options
				(clearance outline)
				(anchor circle)
			)
			(primitives
				(gr_poly
					(pts
						(arc
							(start -0.1778 -0.2794)
							(mid -0.249642 -0.249642)
							(end -0.2794 -0.1778)
						)
						(arc
							(start -0.2794 0.1778)
							(mid -0.249642 0.249642)
							(end -0.1778 0.2794)
						)
						(arc
							(start 0.1778 0.2794)
							(mid 0.249642 0.249642)
							(end 0.2794 0.1778)
						)
						(arc
							(start 0.2794 -0.1778)
							(mid 0.249642 -0.249642)
							(end 0.1778 -0.2794)
						)
					)
					(width 0)
					(fill yes)
				)
			)
		)
	)
	(footprint ""
		(layer "F.Cu")
		(at 9.3218 -454.2028 -90)
		(property "Reference" "R96"
			(at 0 0 270)
			(layer "F.SilkS")
			(hide yes)
			(effects
				(font
					(size 1.27 1.27)
				)
			)
		)
		(property "Value" "4K7R2F-GP"
			(at 0.064008 -3.993896 270)
			(unlocked yes)
			(layer "F.Fab")
			(hide yes)
			(effects
				(font
					(size 1.016 1.016)
					(thickness 0.1524)
				)
			)
		)
		(property "Device Type" "R402H16"
			(at 0.064008 -5.517896 270)
			(unlocked yes)
			(layer "F.Fab")
			(hide yes)
			(effects
				(font
					(size 1.016 1.016)
					(thickness 0.1524)
				)
			)
		)
		(duplicate_pad_numbers_are_jumpers no)
		(fp_line
			(start -0.508 -0.9398)
			(end -0.508 0.9398)
			(stroke
				(width 0.1524)
				(type default)
			)
			(layer "F.SilkS")
		)
		(fp_line
			(start 0.508 -0.9398)
			(end -0.508 -0.9398)
			(stroke
				(width 0.1524)
				(type default)
			)
			(layer "F.SilkS")
		)
		(fp_rect
			(start -0.508 0.9398)
			(end 0.508 -0.9398)
			(stroke
				(width 0)
				(type default)
			)
			(fill no)
			(layer "F.CrtYd")
		)
		(fp_rect
			(start -0.508 0.9398)
			(end 0.508 -0.9398)
			(stroke
				(width 0)
				(type default)
			)
			(fill no)
			(layer "F.Fab")
		)
		(pad "1" smd custom
			(at 0 -0.4445 270)
			(size 0.1397 0.1397)
			(layers "F.Cu" "F.Mask" "F.Paste")
			(net "P12V")
			(options
				(clearance outline)
				(anchor circle)
			)
			(primitives
				(gr_poly
					(pts
						(arc
							(start -0.1778 -0.2794)
							(mid -0.249642 -0.249642)
							(end -0.2794 -0.1778)
						)
						(arc
							(start -0.2794 0.1778)
							(mid -0.249642 0.249642)
							(end -0.1778 0.2794)
						)
						(arc
							(start 0.1778 0.2794)
							(mid 0.249642 0.249642)
							(end 0.2794 0.1778)
						)
						(arc
							(start 0.2794 -0.1778)
							(mid 0.249642 -0.249642)
							(end 0.1778 -0.2794)
						)
					)
					(width 0)
					(fill yes)
				)
			)
		)
		(pad "2" smd custom
			(at 0 0.4445 270)
			(size 0.1397 0.1397)
			(layers "F.Cu" "F.Mask" "F.Paste")
			(net "PWM_OUT_FAN1_NET")
			(options
				(clearance outline)
				(anchor circle)
			)
			(primitives
				(gr_poly
					(pts
						(arc
							(start -0.1778 -0.2794)
							(mid -0.249642 -0.249642)
							(end -0.2794 -0.1778)
						)
						(arc
							(start -0.2794 0.1778)
							(mid -0.249642 0.249642)
							(end -0.1778 0.2794)
						)
						(arc
							(start 0.1778 0.2794)
							(mid 0.249642 0.249642)
							(end 0.2794 0.1778)
						)
						(arc
							(start 0.2794 -0.1778)
							(mid 0.249642 -0.249642)
							(end 0.1778 -0.2794)
						)
					)
					(width 0)
					(fill yes)
				)
			)
		)
	)
	(footprint ""
		(layer "F.Cu")
		(at 16.053308 -287.311338)
		(property "Reference" "R98"
			(at 0 0 0)
			(layer "F.SilkS")
			(hide yes)
			(effects
				(font
					(size 1.27 1.27)
				)
			)
		)
		(property "Value" "27KR3F-GP"
			(at -0.0254 -2.5146 0)
			(unlocked yes)
			(layer "F.Fab")
			(hide yes)
			(effects
				(font
					(size 1.016 1.016)
					(thickness 0.1524)
				)
			)
		)
		(property "Device Type" "R603H22"
			(at -0.0254 -4.0386 0)
			(unlocked yes)
			(layer "F.Fab")
			(hide yes)
			(effects
				(font
					(size 1.016 1.016)
					(thickness 0.1524)
				)
			)
		)
		(duplicate_pad_numbers_are_jumpers no)
		(fp_line
			(start -0.4826 0)
			(end -0.2032 0)
			(stroke
				(width 0.2032)
				(type default)
			)
			(layer "F.SilkS")
		)
		(fp_line
			(start 0.2032 0)
			(end 0.4826 0)
			(stroke
				(width 0.2032)
				(type default)
			)
			(layer "F.SilkS")
		)
		(fp_rect
			(start -0.5842 1.3335)
			(end 0.5842 -1.3335)
			(stroke
				(width 0)
				(type default)
			)
			(fill no)
			(layer "F.CrtYd")
		)
		(fp_rect
			(start -0.5842 1.3335)
			(end 0.5842 -1.3335)
			(stroke
				(width 0)
				(type default)
			)
			(fill no)
			(layer "F.Fab")
		)
		(pad "1" smd custom
			(at 0 -0.762)
			(size 0.2159 0.2159)
			(layers "F.Cu" "F.Mask" "F.Paste")
			(net "FANIN_3")
			(options
				(clearance outline)
				(anchor circle)
			)
			(primitives
				(gr_poly
					(pts
						(arc
							(start -0.3302 -0.4318)
							(mid -0.402042 -0.402042)
							(end -0.4318 -0.3302)
						)
						(arc
							(start -0.4318 0.3302)
							(mid -0.402042 0.402042)
							(end -0.3302 0.4318)
						)
						(arc
							(start 0.3302 0.4318)
							(mid 0.402042 0.402042)
							(end 0.4318 0.3302)
						)
						(arc
							(start 0.4318 -0.3302)
							(mid 0.402042 -0.402042)
							(end 0.3302 -0.4318)
						)
					)
					(width 0)
					(fill yes)
				)
			)
		)
		(pad "2" smd custom
			(at 0 0.762)
			(size 0.2159 0.2159)
			(layers "F.Cu" "F.Mask" "F.Paste")
			(net "FAN_TACH3")
			(options
				(clearance outline)
				(anchor circle)
			)
			(primitives
				(gr_poly
					(pts
						(arc
							(start -0.3302 -0.4318)
							(mid -0.402042 -0.402042)
							(end -0.4318 -0.3302)
						)
						(arc
							(start -0.4318 0.3302)
							(mid -0.402042 0.402042)
							(end -0.3302 0.4318)
						)
						(arc
							(start 0.3302 0.4318)
							(mid 0.402042 0.402042)
							(end 0.4318 0.3302)
						)
						(arc
							(start 0.4318 -0.3302)
							(mid 0.402042 -0.402042)
							(end 0.3302 -0.4318)
						)
					)
					(width 0)
					(fill yes)
				)
			)
		)
	)
)
